(kicad_pcb
	(version 20260206)
	(generator "pcbnew")
	(generator_version "10.0")
	(general
		(thickness 1.6)
		(legacy_teardrops no)
	)
	(paper "A4")
	(title_block
		(title "peb — Lightning_PEB_BRD.brd")
		(comment 1 "Lightning (Wiwynn / Facebook NVMe JBOF) / footprints 2207-2215 of 2563")
	)
	(layers
		(0 "F.Cu" signal "TOP")
		(4 "In1.Cu" signal "L2GND")
		(6 "In2.Cu" signal "L3")
		(8 "In3.Cu" signal "L4VCC")
		(10 "In4.Cu" signal "L5VCC")
		(12 "In5.Cu" signal "L6")
		(14 "In6.Cu" signal "L7GND")
		(2 "B.Cu" signal "BOTTOM")
		(9 "F.Adhes" user "F.Adhesive")
		(11 "B.Adhes" user "B.Adhesive")
		(13 "F.Paste" user "Package Geometry/Pastemask Top")
		(15 "B.Paste" user "Package Geometry/Pastemask Bottom")
		(5 "F.SilkS" user "Ref Des/Silkscreen Top")
		(7 "B.SilkS" user "Ref Des/Silkscreen Bottom")
		(1 "F.Mask" user "Board Geometry/Soldermask Top")
		(3 "B.Mask" user "Board Geometry/Soldermask Bottom")
		(17 "Dwgs.User" user "User.Drawings")
		(19 "Cmts.User" user "User.Comments")
		(21 "Eco1.User" user "User.Eco1")
		(23 "Eco2.User" user "User.Eco2")
		(25 "Edge.Cuts" user "Board Geometry/Outline")
		(27 "Margin" user)
		(31 "F.CrtYd" user "Package Geometry/Place Bound Top")
		(29 "B.CrtYd" user "Package Geometry/Place Bound Bottom")
		(35 "F.Fab" user "Ref Des/Assembly Top")
		(33 "B.Fab" user "Ref Des/Assembly Bottom")
	)
	(footprint ""
		(layer "B.Cu")
		(at 234.8865 -38.00348 -90)
		(property "Reference" "C481"
			(at 0 0 90)
			(layer "B.SilkS")
			(hide yes)
			(effects
				(font
					(size 1.27 1.27)
				)
				(justify mirror)
			)
		)
		(property "Value" "SCD1U16V1KX-1-GP"
			(at 2.8321 -1.7399 270)
			(unlocked yes)
			(layer "B.Fab")
			(hide yes)
			(effects
				(font
					(size 1.016 1.016)
					(thickness 0.1524)
				)
				(justify mirror)
			)
		)
		(property "Device Type" "C0201H13"
			(at 2.8321 -3.2639 270)
			(unlocked yes)
			(layer "B.Fab")
			(hide yes)
			(effects
				(font
					(size 1.016 1.016)
					(thickness 0.1524)
				)
				(justify mirror)
			)
		)
		(duplicate_pad_numbers_are_jumpers no)
		(fp_rect
			(start 0.2794 0.6477)
			(end -0.2794 -0.6477)
			(stroke
				(width 0)
				(type default)
			)
			(fill no)
			(layer "B.CrtYd")
		)
		(fp_rect
			(start 0.2794 0.6477)
			(end -0.2794 -0.6477)
			(stroke
				(width 0)
				(type default)
			)
			(fill no)
			(layer "B.Fab")
		)
		(pad "1" smd custom
			(at 0 -0.2794 90)
			(size 0.0762 0.0762)
			(layers "B.Cu" "B.Mask" "B.Paste")
			(net "DUT_VDDO")
			(options
				(clearance outline)
				(anchor circle)
			)
			(primitives
				(gr_poly
					(pts
						(arc
							(start 0.1524 0.127)
							(mid 0.137521 0.162921)
							(end 0.1016 0.1778)
						)
						(arc
							(start -0.1016 0.1778)
							(mid -0.137521 0.162921)
							(end -0.1524 0.127)
						)
						(arc
							(start -0.1524 -0.127)
							(mid -0.137521 -0.162921)
							(end -0.1016 -0.1778)
						)
						(arc
							(start 0.1016 -0.1778)
							(mid 0.137521 -0.162921)
							(end 0.1524 -0.127)
						)
					)
					(width 0)
					(fill yes)
				)
			)
		)
		(pad "2" smd custom
			(at 0 0.2794 90)
			(size 0.0762 0.0762)
			(layers "B.Cu" "B.Mask" "B.Paste")
			(net "GND")
			(options
				(clearance outline)
				(anchor circle)
			)
			(primitives
				(gr_poly
					(pts
						(arc
							(start 0.1524 0.127)
							(mid 0.137521 0.162921)
							(end 0.1016 0.1778)
						)
						(arc
							(start -0.1016 0.1778)
							(mid -0.137521 0.162921)
							(end -0.1524 0.127)
						)
						(arc
							(start -0.1524 -0.127)
							(mid -0.137521 -0.162921)
							(end -0.1016 -0.1778)
						)
						(arc
							(start 0.1016 -0.1778)
							(mid 0.137521 -0.162921)
							(end 0.1524 -0.127)
						)
					)
					(width 0)
					(fill yes)
				)
			)
		)
	)
	(footprint ""
		(layer "B.Cu")
		(at 78.486 -189.611)
		(property "Reference" "U69"
			(at 0 0 0)
			(layer "B.SilkS")
			(hide yes)
			(effects
				(font
					(size 1.27 1.27)
				)
				(justify mirror)
			)
		)
		(property "Value" "SN74LVC1G08DCKR-GP"
			(at 2.3368 -8.6868 0)
			(unlocked yes)
			(layer "B.Fab")
			(hide yes)
			(effects
				(font
					(size 1.016 1.016)
					(thickness 0.1524)
				)
				(justify mirror)
			)
		)
		(property "Device Type" "SC70-5H44"
			(at 2.3114 -10.414 0)
			(unlocked yes)
			(layer "B.Fab")
			(hide yes)
			(effects
				(font
					(size 1.016 1.016)
					(thickness 0.1524)
				)
				(justify mirror)
			)
		)
		(duplicate_pad_numbers_are_jumpers no)
		(fp_line
			(start -1.3843 -1.8034)
			(end -1.3843 -1.1176)
			(stroke
				(width 0.3302)
				(type default)
			)
			(layer "B.SilkS")
		)
		(fp_line
			(start -1.27 -1.7018)
			(end -1.27 1.7018)
			(stroke
				(width 0.1524)
				(type default)
			)
			(layer "B.SilkS")
		)
		(fp_line
			(start -1.27 1.7018)
			(end 1.27 1.7018)
			(stroke
				(width 0.1524)
				(type default)
			)
			(layer "B.SilkS")
		)
		(fp_line
			(start -0.6604 -1.8034)
			(end -1.3843 -1.8034)
			(stroke
				(width 0.3302)
				(type default)
			)
			(layer "B.SilkS")
		)
		(fp_line
			(start 1.27 -1.7018)
			(end -1.27 -1.7018)
			(stroke
				(width 0.1524)
				(type default)
			)
			(layer "B.SilkS")
		)
		(fp_line
			(start 1.27 1.7018)
			(end 1.27 -1.7018)
			(stroke
				(width 0.1524)
				(type default)
			)
			(layer "B.SilkS")
		)
		(fp_rect
			(start 1.524 1.9558)
			(end -1.524 -1.9558)
			(stroke
				(width 0)
				(type default)
			)
			(fill no)
			(layer "B.CrtYd")
		)
		(fp_poly
			(pts
				(xy 1.524 -1.9558) (xy -1.524 -1.9558) (xy -1.524 1.9558) (xy 1.524 1.9558)
			)
			(stroke
				(width 0)
				(type default)
			)
			(fill no)
			(layer "B.Fab")
		)
		(pad "1" smd rect
			(at -0.65024 -0.8255 180)
			(size 0.4064 1.2192)
			(layers "B.Cu" "B.Mask" "B.Paste")
			(net "BMC_SSD_RST#0_A5")
		)
		(pad "2" smd rect
			(at 0 -0.8255 180)
			(size 0.4064 1.2192)
			(layers "B.Cu" "B.Mask" "B.Paste")
			(net "SSD_PERST#0_B5")
		)
		(pad "3" smd rect
			(at 0.65024 -0.8255 180)
			(size 0.4064 1.2192)
			(layers "B.Cu" "B.Mask" "B.Paste")
			(net "GND")
		)
		(pad "4" smd rect
			(at 0.65024 0.8255 180)
			(size 0.4064 1.2192)
			(layers "B.Cu" "B.Mask" "B.Paste")
			(net "SSD_PERST_Y5")
		)
		(pad "5" smd rect
			(at -0.65024 0.8255 180)
			(size 0.4064 1.2192)
			(layers "B.Cu" "B.Mask" "B.Paste")
			(net "P3V3_STBY")
		)
	)
	(footprint ""
		(layer "B.Cu")
		(at 43.942 -137.795)
		(property "Reference" "TP229"
			(at 0 0 0)
			(layer "B.SilkS")
			(hide yes)
			(effects
				(font
					(size 1.27 1.27)
				)
				(justify mirror)
			)
		)
		(property "Value" "TPAD28-2-GP"
			(at 0.0127 -1.6637 0)
			(unlocked yes)
			(layer "B.Fab")
			(hide yes)
			(effects
				(font
					(size 1.016 1.016)
					(thickness 0.1524)
				)
				(justify mirror)
			)
		)
		(property "Device Type" "TPAD28"
			(at 0.0127 -3.1877 0)
			(unlocked yes)
			(layer "B.Fab")
			(hide yes)
			(effects
				(font
					(size 1.016 1.016)
					(thickness 0.1524)
				)
				(justify mirror)
			)
		)
		(duplicate_pad_numbers_are_jumpers no)
		(fp_poly
			(pts
				(arc
					(start 0.3556 0)
					(mid -0.3556 0)
					(end 0.3556 0)
				)
			)
			(stroke
				(width 0)
				(type default)
			)
			(fill no)
			(layer "B.CrtYd")
		)
		(fp_poly
			(pts
				(arc
					(start 0.6096 0)
					(mid -0.6096 0)
					(end 0.6096 0)
				)
			)
			(stroke
				(width 0)
				(type default)
			)
			(fill no)
			(layer "B.Fab")
		)
		(pad "1" smd circle
			(at 0 0 180)
			(size 0.7112 0.7112)
			(layers "B.Cu" "B.Mask" "B.Paste")
			(net "TP_GPIOO0")
		)
	)
	(footprint ""
		(layer "B.Cu")
		(at 237.1598 -54.0004 -90)
		(property "Reference" "C28"
			(at 0 0 90)
			(layer "B.SilkS")
			(hide yes)
			(effects
				(font
					(size 1.27 1.27)
				)
				(justify mirror)
			)
		)
		(property "Value" "SCD1U16V1KX-1-GP"
			(at 2.8321 -1.7399 270)
			(unlocked yes)
			(layer "B.Fab")
			(hide yes)
			(effects
				(font
					(size 1.016 1.016)
					(thickness 0.1524)
				)
				(justify mirror)
			)
		)
		(property "Device Type" "C0201H13"
			(at 2.8321 -3.2639 270)
			(unlocked yes)
			(layer "B.Fab")
			(hide yes)
			(effects
				(font
					(size 1.016 1.016)
					(thickness 0.1524)
				)
				(justify mirror)
			)
		)
		(duplicate_pad_numbers_are_jumpers no)
		(fp_rect
			(start 0.2794 0.6477)
			(end -0.2794 -0.6477)
			(stroke
				(width 0)
				(type default)
			)
			(fill no)
			(layer "B.CrtYd")
		)
		(fp_rect
			(start 0.2794 0.6477)
			(end -0.2794 -0.6477)
			(stroke
				(width 0)
				(type default)
			)
			(fill no)
			(layer "B.Fab")
		)
		(pad "1" smd custom
			(at 0 -0.2794 90)
			(size 0.0762 0.0762)
			(layers "B.Cu" "B.Mask" "B.Paste")
			(net "DUT_VDD")
			(options
				(clearance outline)
				(anchor circle)
			)
			(primitives
				(gr_poly
					(pts
						(arc
							(start 0.1524 0.127)
							(mid 0.137521 0.162921)
							(end 0.1016 0.1778)
						)
						(arc
							(start -0.1016 0.1778)
							(mid -0.137521 0.162921)
							(end -0.1524 0.127)
						)
						(arc
							(start -0.1524 -0.127)
							(mid -0.137521 -0.162921)
							(end -0.1016 -0.1778)
						)
						(arc
							(start 0.1016 -0.1778)
							(mid 0.137521 -0.162921)
							(end 0.1524 -0.127)
						)
					)
					(width 0)
					(fill yes)
				)
			)
		)
		(pad "2" smd custom
			(at 0 0.2794 90)
			(size 0.0762 0.0762)
			(layers "B.Cu" "B.Mask" "B.Paste")
			(net "GND")
			(options
				(clearance outline)
				(anchor circle)
			)
			(primitives
				(gr_poly
					(pts
						(arc
							(start 0.1524 0.127)
							(mid 0.137521 0.162921)
							(end 0.1016 0.1778)
						)
						(arc
							(start -0.1016 0.1778)
							(mid -0.137521 0.162921)
							(end -0.1524 0.127)
						)
						(arc
							(start -0.1524 -0.127)
							(mid -0.137521 -0.162921)
							(end -0.1016 -0.1778)
						)
						(arc
							(start 0.1016 -0.1778)
							(mid 0.137521 -0.162921)
							(end 0.1524 -0.127)
						)
					)
					(width 0)
					(fill yes)
				)
			)
		)
	)
	(footprint ""
		(layer "B.Cu")
		(at 248.59996 -38.999922 -90)
		(property "Reference" "TP281"
			(at 0 0 90)
			(layer "B.SilkS")
			(hide yes)
			(effects
				(font
					(size 1.27 1.27)
				)
				(justify mirror)
			)
		)
		(property "Value" "TPAD28-2-GP"
			(at 0.0127 -1.6637 270)
			(unlocked yes)
			(layer "B.Fab")
			(hide yes)
			(effects
				(font
					(size 1.016 1.016)
					(thickness 0.1524)
				)
				(justify mirror)
			)
		)
		(property "Device Type" "TPAD28"
			(at 0.0127 -3.1877 270)
			(unlocked yes)
			(layer "B.Fab")
			(hide yes)
			(effects
				(font
					(size 1.016 1.016)
					(thickness 0.1524)
				)
				(justify mirror)
			)
		)
		(duplicate_pad_numbers_are_jumpers no)
		(fp_poly
			(pts
				(arc
					(start 0 -0.3556)
					(mid 0 0.3556)
					(end 0 -0.3556)
				)
			)
			(stroke
				(width 0)
				(type default)
			)
			(fill no)
			(layer "B.CrtYd")
		)
		(fp_poly
			(pts
				(arc
					(start 0 -0.6096)
					(mid 0 0.6096)
					(end 0 -0.6096)
				)
			)
			(stroke
				(width 0)
				(type default)
			)
			(fill no)
			(layer "B.Fab")
		)
		(pad "1" smd circle
			(at 0 0 90)
			(size 0.7112 0.7112)
			(layers "B.Cu" "B.Mask" "B.Paste")
			(net "TWI_SRST#2")
		)
	)
	(footprint ""
		(layer "B.Cu")
		(at 43.434 -118.872)
		(property "Reference" "TP93"
			(at 0 0 0)
			(layer "B.SilkS")
			(hide yes)
			(effects
				(font
					(size 1.27 1.27)
				)
				(justify mirror)
			)
		)
		(property "Value" "TPAD28-2-GP"
			(at 0.0127 -1.6637 0)
			(unlocked yes)
			(layer "B.Fab")
			(hide yes)
			(effects
				(font
					(size 1.016 1.016)
					(thickness 0.1524)
				)
				(justify mirror)
			)
		)
		(property "Device Type" "TPAD28"
			(at 0.0127 -3.1877 0)
			(unlocked yes)
			(layer "B.Fab")
			(hide yes)
			(effects
				(font
					(size 1.016 1.016)
					(thickness 0.1524)
				)
				(justify mirror)
			)
		)
		(duplicate_pad_numbers_are_jumpers no)
		(fp_poly
			(pts
				(arc
					(start 0.3556 0)
					(mid -0.3556 0)
					(end 0.3556 0)
				)
			)
			(stroke
				(width 0)
				(type default)
			)
			(fill no)
			(layer "B.CrtYd")
		)
		(fp_poly
			(pts
				(arc
					(start 0.6096 0)
					(mid -0.6096 0)
					(end 0.6096 0)
				)
			)
			(stroke
				(width 0)
				(type default)
			)
			(fill no)
			(layer "B.Fab")
		)
		(pad "1" smd circle
			(at 0 0 180)
			(size 0.7112 0.7112)
			(layers "B.Cu" "B.Mask" "B.Paste")
			(net "TP_GPIOH4")
		)
	)
	(footprint ""
		(layer "B.Cu")
		(at 227.6856 -37.004752 -90)
		(property "Reference" "C569"
			(at 0 0 90)
			(layer "B.SilkS")
			(hide yes)
			(effects
				(font
					(size 1.27 1.27)
				)
				(justify mirror)
			)
		)
		(property "Value" "SCD1U16V1KX-1-GP"
			(at 2.8321 -1.7399 270)
			(unlocked yes)
			(layer "B.Fab")
			(hide yes)
			(effects
				(font
					(size 1.016 1.016)
					(thickness 0.1524)
				)
				(justify mirror)
			)
		)
		(property "Device Type" "C0201H13"
			(at 2.8321 -3.2639 270)
			(unlocked yes)
			(layer "B.Fab")
			(hide yes)
			(effects
				(font
					(size 1.016 1.016)
					(thickness 0.1524)
				)
				(justify mirror)
			)
		)
		(duplicate_pad_numbers_are_jumpers no)
		(fp_rect
			(start 0.2794 0.6477)
			(end -0.2794 -0.6477)
			(stroke
				(width 0)
				(type default)
			)
			(fill no)
			(layer "B.CrtYd")
		)
		(fp_rect
			(start 0.2794 0.6477)
			(end -0.2794 -0.6477)
			(stroke
				(width 0)
				(type default)
			)
			(fill no)
			(layer "B.Fab")
		)
		(pad "1" smd custom
			(at 0 -0.2794 90)
			(size 0.0762 0.0762)
			(layers "B.Cu" "B.Mask" "B.Paste")
			(net "DUT_AVD_PCIE")
			(options
				(clearance outline)
				(anchor circle)
			)
			(primitives
				(gr_poly
					(pts
						(arc
							(start 0.1524 0.127)
							(mid 0.137521 0.162921)
							(end 0.1016 0.1778)
						)
						(arc
							(start -0.1016 0.1778)
							(mid -0.137521 0.162921)
							(end -0.1524 0.127)
						)
						(arc
							(start -0.1524 -0.127)
							(mid -0.137521 -0.162921)
							(end -0.1016 -0.1778)
						)
						(arc
							(start 0.1016 -0.1778)
							(mid 0.137521 -0.162921)
							(end 0.1524 -0.127)
						)
					)
					(width 0)
					(fill yes)
				)
			)
		)
		(pad "2" smd custom
			(at 0 0.2794 90)
			(size 0.0762 0.0762)
			(layers "B.Cu" "B.Mask" "B.Paste")
			(net "GND")
			(options
				(clearance outline)
				(anchor circle)
			)
			(primitives
				(gr_poly
					(pts
						(arc
							(start 0.1524 0.127)
							(mid 0.137521 0.162921)
							(end 0.1016 0.1778)
						)
						(arc
							(start -0.1016 0.1778)
							(mid -0.137521 0.162921)
							(end -0.1524 0.127)
						)
						(arc
							(start -0.1524 -0.127)
							(mid -0.137521 -0.162921)
							(end -0.1016 -0.1778)
						)
						(arc
							(start 0.1016 -0.1778)
							(mid 0.137521 -0.162921)
							(end 0.1524 -0.127)
						)
					)
					(width 0)
					(fill yes)
				)
			)
		)
	)
	(footprint ""
		(layer "B.Cu")
		(at 19.9136 -185.2422 -90)
		(property "Reference" "R2122"
			(at 0 0 90)
			(layer "B.SilkS")
			(hide yes)
			(effects
				(font
					(size 1.27 1.27)
				)
				(justify mirror)
			)
		)
		(property "Value" "10R2F-L-GP"
			(at -0.064008 -3.993896 270)
			(unlocked yes)
			(layer "B.Fab")
			(hide yes)
			(effects
				(font
					(size 1.016 1.016)
					(thickness 0.1524)
				)
				(justify mirror)
			)
		)
		(property "Device Type" "R402H14"
			(at -0.064008 -5.517896 270)
			(unlocked yes)
			(layer "B.Fab")
			(hide yes)
			(effects
				(font
					(size 1.016 1.016)
					(thickness 0.1524)
				)
				(justify mirror)
			)
		)
		(duplicate_pad_numbers_are_jumpers no)
		(fp_line
			(start -0.508 -0.9398)
			(end 0.508 -0.9398)
			(stroke
				(width 0.1524)
				(type default)
			)
			(layer "B.SilkS")
		)
		(fp_line
			(start 0.508 -0.9398)
			(end 0.508 0.9398)
			(stroke
				(width 0.1524)
				(type default)
			)
			(layer "B.SilkS")
		)
		(fp_rect
			(start 0.508 0.9398)
			(end -0.508 -0.9398)
			(stroke
				(width 0)
				(type default)
			)
			(fill no)
			(layer "B.CrtYd")
		)
		(fp_rect
			(start 0.508 0.9398)
			(end -0.508 -0.9398)
			(stroke
				(width 0)
				(type default)
			)
			(fill no)
			(layer "B.Fab")
		)
		(pad "1" smd custom
			(at 0 -0.4445 90)
			(size 0.1397 0.1397)
			(layers "B.Cu" "B.Mask" "B.Paste")
			(net "MB0_CM_SENSE_R1_N")
			(options
				(clearance outline)
				(anchor circle)
			)
			(primitives
				(gr_poly
					(pts
						(arc
							(start -0.1778 0.2794)
							(mid -0.249642 0.249642)
							(end -0.2794 0.1778)
						)
						(arc
							(start -0.2794 -0.1778)
							(mid -0.249642 -0.249642)
							(end -0.1778 -0.2794)
						)
						(arc
							(start 0.1778 -0.2794)
							(mid 0.249642 -0.249642)
							(end 0.2794 -0.1778)
						)
						(arc
							(start 0.2794 0.1778)
							(mid 0.249642 0.249642)
							(end 0.1778 0.2794)
						)
					)
					(width 0)
					(fill yes)
				)
			)
		)
		(pad "2" smd custom
			(at 0 0.4445 90)
			(size 0.1397 0.1397)
			(layers "B.Cu" "B.Mask" "B.Paste")
			(net "MB0_CM_SENSE_N")
			(options
				(clearance outline)
				(anchor circle)
			)
			(primitives
				(gr_poly
					(pts
						(arc
							(start -0.1778 0.2794)
							(mid -0.249642 0.249642)
							(end -0.2794 0.1778)
						)
						(arc
							(start -0.2794 -0.1778)
							(mid -0.249642 -0.249642)
							(end -0.1778 -0.2794)
						)
						(arc
							(start 0.1778 -0.2794)
							(mid 0.249642 -0.249642)
							(end 0.2794 -0.1778)
						)
						(arc
							(start 0.2794 0.1778)
							(mid 0.249642 0.249642)
							(end 0.1778 0.2794)
						)
					)
					(width 0)
					(fill yes)
				)
			)
		)
	)
	(footprint ""
		(layer "B.Cu")
		(at 253.746 -26.1112 180)
		(property "Reference" "R760"
			(at 0 0 0)
			(layer "B.SilkS")
			(hide yes)
			(effects
				(font
					(size 1.27 1.27)
				)
				(justify mirror)
			)
		)
		(property "Value" "3K3R2F-2-GP"
			(at -0.064008 -3.993896 180)
			(unlocked yes)
			(layer "B.Fab")
			(hide yes)
			(effects
				(font
					(size 1.016 1.016)
					(thickness 0.1524)
				)
				(justify mirror)
			)
		)
		(property "Device Type" "R402H16"
			(at -0.064008 -5.517896 180)
			(unlocked yes)
			(layer "B.Fab")
			(hide yes)
			(effects
				(font
					(size 1.016 1.016)
					(thickness 0.1524)
				)
				(justify mirror)
			)
		)
		(duplicate_pad_numbers_are_jumpers no)
		(fp_line
			(start 0.508 -0.9398)
			(end 0.508 0.9398)
			(stroke
				(width 0.1524)
				(type default)
			)
			(layer "B.SilkS")
		)
		(fp_line
			(start -0.508 -0.9398)
			(end 0.508 -0.9398)
			(stroke
				(width 0.1524)
				(type default)
			)
			(layer "B.SilkS")
		)
		(fp_rect
			(start 0.508 0.9398)
			(end -0.508 -0.9398)
			(stroke
				(width 0)
				(type default)
			)
			(fill no)
			(layer "B.CrtYd")
		)
		(fp_rect
			(start 0.508 0.9398)
			(end -0.508 -0.9398)
			(stroke
				(width 0)
				(type default)
			)
			(fill no)
			(layer "B.Fab")
		)
		(pad "1" smd custom
			(at 0 -0.4445)
			(size 0.1397 0.1397)
			(layers "B.Cu" "B.Mask" "B.Paste")
			(net "P3V3_GPIO")
			(options
				(clearance outline)
				(anchor circle)
			)
			(primitives
				(gr_poly
					(pts
						(arc
							(start -0.1778 0.2794)
							(mid -0.249642 0.249642)
							(end -0.2794 0.1778)
						)
						(arc
							(start -0.2794 -0.1778)
							(mid -0.249642 -0.249642)
							(end -0.1778 -0.2794)
						)
						(arc
							(start 0.1778 -0.2794)
							(mid 0.249642 -0.249642)
							(end 0.2794 -0.1778)
						)
						(arc
							(start 0.2794 0.1778)
							(mid 0.249642 0.249642)
							(end 0.1778 0.2794)
						)
					)
					(width 0)
					(fill yes)
				)
			)
		)
		(pad "2" smd custom
			(at 0 0.4445)
			(size 0.1397 0.1397)
			(layers "B.Cu" "B.Mask" "B.Paste")
			(net "TWI_SDA0")
			(options
				(clearance outline)
				(anchor circle)
			)
			(primitives
				(gr_poly
					(pts
						(arc
							(start -0.1778 0.2794)
							(mid -0.249642 0.249642)
							(end -0.2794 0.1778)
						)
						(arc
							(start -0.2794 -0.1778)
							(mid -0.249642 -0.249642)
							(end -0.1778 -0.2794)
						)
						(arc
							(start 0.1778 -0.2794)
							(mid 0.249642 -0.249642)
							(end 0.2794 -0.1778)
						)
						(arc
							(start 0.2794 0.1778)
							(mid 0.249642 0.249642)
							(end 0.1778 0.2794)
						)
					)
					(width 0)
					(fill yes)
				)
			)
		)
	)
)
